(kicad_pcb
	(version 20260206)
	(generator "pcbnew")
	(generator_version "10.0")
	(general
		(thickness 1.6)
		(legacy_teardrops no)
	)
	(paper "A4")
	(title_block
		(title "timecard-production-celestica-r4006 — R4006-B0001-02_R01.brd")
		(comment 1 "Time Appliance Project (Time Card) / footprints 317-320 of 1113")
	)
	(layers
		(0 "F.Cu" signal "TOP")
		(4 "In1.Cu" signal "L02_GND1")
		(6 "In2.Cu" signal "L03_SIG1")
		(8 "In3.Cu" signal "L04_GND2")
		(10 "In4.Cu" signal "L05_VCC1")
		(12 "In5.Cu" signal "L06_VCC2")
		(14 "In6.Cu" signal "L07_GND3")
		(16 "In7.Cu" signal "L08_SIG2")
		(18 "In8.Cu" signal "L09_GND4")
		(2 "B.Cu" signal "BOTTOM")
		(9 "F.Adhes" user "F.Adhesive")
		(11 "B.Adhes" user "B.Adhesive")
		(13 "F.Paste" user "Package Geometry/Pastemask Top")
		(15 "B.Paste" user "Package Geometry/Pastemask Bottom")
		(5 "F.SilkS" user "Ref Des/Silkscreen Top")
		(7 "B.SilkS" user "Ref Des/Silkscreen Bottom")
		(1 "F.Mask" user "Board Geometry/Soldermask Top")
		(3 "B.Mask" user "Board Geometry/Soldermask Bottom")
		(17 "Dwgs.User" user "User.Drawings")
		(19 "Cmts.User" user "User.Comments")
		(21 "Eco1.User" user "User.Eco1")
		(23 "Eco2.User" user "User.Eco2")
		(25 "Edge.Cuts" user "Board Geometry/Outline")
		(27 "Margin" user)
		(31 "F.CrtYd" user "Package Geometry/Place Bound Top")
		(29 "B.CrtYd" user "Package Geometry/Place Bound Bottom")
		(35 "F.Fab" user "Ref Des/Assembly Top")
		(33 "B.Fab" user "Ref Des/Assembly Bottom")
	)
	(footprint ""
		(layer "F.Cu")
		(at 105.537 -93.345)
		(property "Reference" "U30"
			(at -0.254 -3.26263 0)
			(unlocked yes)
			(layer "F.SilkS")
			(effects
				(font
					(size 0.7874 0.5842)
					(thickness 0.1524)
				)
			)
		)
		(property "Value" ""
			(at 0 0 0)
			(layer "F.Fab")
			(effects
				(font
					(size 1.27 1.27)
				)
			)
		)
		(property "Device Type" "TS3A5018PWR_TSSOP16-G220-10324A"
			(at 0 0.924306 0)
			(unlocked yes)
			(layer "F.Fab")
			(hide yes)
			(effects
				(font
					(size 0.7874 0.5842)
					(thickness 0.000001)
				)
			)
		)
		(property "User Part Number" "PARTNUM*"
			(at 0.254 1.940306 0)
			(unlocked yes)
			(layer "Cmts.User")
			(hide yes)
			(effects
				(font
					(size 0.7874 0.5842)
					(thickness 0.000001)
				)
			)
		)
		(duplicate_pad_numbers_are_jumpers no)
		(fp_line
			(start -4.0767 -2.7559)
			(end 4.0767 -2.7559)
			(stroke
				(width 0.1)
				(type default)
			)
			(layer "F.SilkS")
		)
		(fp_line
			(start -4.0767 2.7559)
			(end -4.0767 -2.7559)
			(stroke
				(width 0.1)
				(type default)
			)
			(layer "F.SilkS")
		)
		(fp_line
			(start 4.0767 -2.7559)
			(end 4.0767 2.7559)
			(stroke
				(width 0.1)
				(type default)
			)
			(layer "F.SilkS")
		)
		(fp_line
			(start 4.0767 2.7559)
			(end -4.0767 2.7559)
			(stroke
				(width 0.1)
				(type default)
			)
			(layer "F.SilkS")
		)
		(fp_poly
			(pts
				(arc
					(start -4.3815 -2.2225)
					(mid -5.1435 -2.2225)
					(end -4.3815 -2.2225)
				)
			)
			(stroke
				(width 0)
				(type default)
			)
			(fill yes)
			(layer "F.SilkS")
		)
		(fp_rect
			(start -4.3307 3.0099)
			(end 4.3307 -3.0099)
			(stroke
				(width 0)
				(type default)
			)
			(fill no)
			(layer "F.CrtYd")
		)
		(fp_line
			(start -2.1971 -2.5019)
			(end 2.1971 -2.5019)
			(stroke
				(width 0.1)
				(type default)
			)
			(layer "F.Fab")
		)
		(fp_line
			(start -2.1971 2.5019)
			(end -2.1971 -2.5019)
			(stroke
				(width 0.1)
				(type default)
			)
			(layer "F.Fab")
		)
		(fp_line
			(start 2.1971 -2.5019)
			(end 2.1971 2.5019)
			(stroke
				(width 0.1)
				(type default)
			)
			(layer "F.Fab")
		)
		(fp_line
			(start 2.1971 2.5019)
			(end -2.1971 2.5019)
			(stroke
				(width 0.1)
				(type default)
			)
			(layer "F.Fab")
		)
		(fp_poly
			(pts
				(arc
					(start -1.114298 -1.942084)
					(mid -1.914398 -1.942084)
					(end -1.114298 -1.942084)
				)
			)
			(stroke
				(width 0)
				(type default)
			)
			(fill yes)
			(layer "F.Fab")
		)
		(fp_text user "8"
			(at -4.699 2.57937 0)
			(unlocked yes)
			(layer "F.SilkS")
			(effects
				(font
					(size 0.7874 0.5842)
					(thickness 0.1524)
				)
			)
		)
		(fp_text user "16"
			(at 4.572 -2.50825 0)
			(unlocked yes)
			(layer "F.SilkS")
			(effects
				(font
					(size 0.635 0.4064)
					(thickness 0.1524)
				)
			)
		)
		(fp_text user "9"
			(at 4.699 2.83337 0)
			(unlocked yes)
			(layer "F.SilkS")
			(effects
				(font
					(size 0.7874 0.5842)
					(thickness 0.1524)
				)
			)
		)
		(fp_text user "8"
			(at -4.572 2.18567 0)
			(unlocked yes)
			(layer "F.Fab")
			(effects
				(font
					(size 0.7874 0.5842)
					(thickness 0.1524)
				)
			)
		)
		(fp_text user "9"
			(at 4.5466 2.31267 0)
			(unlocked yes)
			(layer "F.Fab")
			(effects
				(font
					(size 0.7874 0.5842)
					(thickness 0.1524)
				)
			)
		)
		(fp_text user "16"
			(at 4.572 -3.00863 0)
			(unlocked yes)
			(layer "F.Fab")
			(effects
				(font
					(size 0.7874 0.5842)
					(thickness 0.1524)
				)
			)
		)
		(pad "1" smd rect
			(at -3.0353 -2.275078 90)
			(size 0.3556 1.5748)
			(layers "F.Cu" "F.Mask" "F.Paste")
			(net "MUX1_SEL")
		)
		(pad "2" smd rect
			(at -3.0353 -1.625092 90)
			(size 0.3556 1.5748)
			(layers "F.Cu" "F.Mask" "F.Paste")
			(net "FT4232_FPGA_TCK")
		)
		(pad "3" smd rect
			(at -3.0353 -0.975106 90)
			(size 0.3556 1.5748)
			(layers "F.Cu" "F.Mask" "F.Paste")
			(net "FT4232_SPI_CLK")
		)
		(pad "4" smd rect
			(at -3.0353 -0.32512 90)
			(size 0.3556 1.5748)
			(layers "F.Cu" "F.Mask" "F.Paste")
			(net "FT4232_TCK_SCLK")
		)
		(pad "5" smd rect
			(at -3.0353 0.32512 90)
			(size 0.3556 1.5748)
			(layers "F.Cu" "F.Mask" "F.Paste")
			(net "FT4232_FPGA_TDI")
		)
		(pad "6" smd rect
			(at -3.0353 0.975106 90)
			(size 0.3556 1.5748)
			(layers "F.Cu" "F.Mask" "F.Paste")
			(net "FT4232_SPI_MOSI")
		)
		(pad "7" smd rect
			(at -3.0353 1.625092 90)
			(size 0.3556 1.5748)
			(layers "F.Cu" "F.Mask" "F.Paste")
			(net "FT4232_TDI_MOSI")
		)
		(pad "8" smd rect
			(at -3.0353 2.275078 90)
			(size 0.3556 1.5748)
			(layers "F.Cu" "F.Mask" "F.Paste")
			(net "SG")
		)
		(pad "9" smd rect
			(at 3.0353 2.275078 90)
			(size 0.3556 1.5748)
			(layers "F.Cu" "F.Mask" "F.Paste")
			(net "FT4232_TDO_MISO")
		)
		(pad "10" smd rect
			(at 3.0353 1.625092 90)
			(size 0.3556 1.5748)
			(layers "F.Cu" "F.Mask" "F.Paste")
			(net "FT4232_SPI_MISO")
		)
		(pad "11" smd rect
			(at 3.0353 0.975106 90)
			(size 0.3556 1.5748)
			(layers "F.Cu" "F.Mask" "F.Paste")
			(net "FT4232_FPGA_TDO")
		)
		(pad "12" smd rect
			(at 3.0353 0.32512 90)
			(size 0.3556 1.5748)
			(layers "F.Cu" "F.Mask" "F.Paste")
			(net "FT4232_TMS_SPICS_N")
		)
		(pad "13" smd rect
			(at 3.0353 -0.32512 90)
			(size 0.3556 1.5748)
			(layers "F.Cu" "F.Mask" "F.Paste")
			(net "FT4232_SPI_CS_N")
		)
		(pad "14" smd rect
			(at 3.0353 -0.975106 90)
			(size 0.3556 1.5748)
			(layers "F.Cu" "F.Mask" "F.Paste")
			(net "FT4232_FPGA_TMS")
		)
		(pad "15" smd rect
			(at 3.0353 -1.625092 90)
			(size 0.3556 1.5748)
			(layers "F.Cu" "F.Mask" "F.Paste")
			(net "UNNAMED_524_POWERMOS3PNCHV1_I44")
		)
		(pad "16" smd rect
			(at 3.0353 -2.275078 90)
			(size 0.3556 1.5748)
			(layers "F.Cu" "F.Mask" "F.Paste")
			(net "XP3R3V_FPGA")
		)
	)
	(footprint ""
		(layer "F.Cu")
		(at 97.4598 -70.485)
		(property "Reference" "R185"
			(at -28.1178 -18.75663 0)
			(unlocked yes)
			(layer "F.SilkS")
			(effects
				(font
					(size 0.7874 0.5842)
					(thickness 0.1524)
				)
			)
		)
		(property "Value" "VAL*"
			(at 0.0508 2.245106 0)
			(unlocked yes)
			(layer "F.Fab")
			(hide yes)
			(effects
				(font
					(size 0.7874 0.5842)
					(thickness 0.1524)
				)
			)
		)
		(property "User Part Number" "PARTNUM*"
			(at 0.0762 4.302506 0)
			(unlocked yes)
			(layer "Cmts.User")
			(hide yes)
			(effects
				(font
					(size 0.7874 0.5842)
					(thickness 0.1524)
				)
			)
		)
		(property "Device Type" "RESISTOR-G155-04221-01,4.22KOHA"
			(at 0.0762 1.254506 0)
			(unlocked yes)
			(layer "F.Fab")
			(hide yes)
			(effects
				(font
					(size 0.7874 0.5842)
					(thickness 0.1524)
				)
			)
		)
		(property "Tolerance" "TOL*"
			(at 0.0508 3.261106 0)
			(unlocked yes)
			(layer "Cmts.User")
			(hide yes)
			(effects
				(font
					(size 0.7874 0.5842)
					(thickness 0.1524)
				)
			)
		)
		(duplicate_pad_numbers_are_jumpers no)
		(fp_line
			(start -1.143 -0.5588)
			(end -1.143 0.5588)
			(stroke
				(width 0.1)
				(type default)
			)
			(layer "F.SilkS")
		)
		(fp_line
			(start -1.143 0.5588)
			(end 1.143 0.5588)
			(stroke
				(width 0.1)
				(type default)
			)
			(layer "F.SilkS")
		)
		(fp_line
			(start 1.143 -0.5588)
			(end -1.143 -0.5588)
			(stroke
				(width 0.1)
				(type default)
			)
			(layer "F.SilkS")
		)
		(fp_line
			(start 1.143 0.5588)
			(end 1.143 -0.5588)
			(stroke
				(width 0.1)
				(type default)
			)
			(layer "F.SilkS")
		)
		(fp_rect
			(start -1.143 -0.5588)
			(end 1.143 0.5588)
			(stroke
				(width 0)
				(type default)
			)
			(fill no)
			(layer "F.CrtYd")
		)
		(fp_line
			(start -0.508 -0.3048)
			(end -0.508 0.3048)
			(stroke
				(width 0.1)
				(type default)
			)
			(layer "F.Fab")
		)
		(fp_line
			(start -0.508 0.3048)
			(end 0.508 0.3048)
			(stroke
				(width 0.1)
				(type default)
			)
			(layer "F.Fab")
		)
		(fp_line
			(start 0.508 -0.3048)
			(end -0.508 -0.3048)
			(stroke
				(width 0.1)
				(type default)
			)
			(layer "F.Fab")
		)
		(fp_line
			(start 0.508 0.3048)
			(end 0.508 -0.3048)
			(stroke
				(width 0.1)
				(type default)
			)
			(layer "F.Fab")
		)
		(pad "1" smd rect
			(at -0.5334 0)
			(size 0.7112 0.6096)
			(layers "F.Cu" "F.Mask" "F.Paste")
			(net "XP1R2V_FPGA")
		)
		(pad "2" smd rect
			(at 0.5334 0)
			(size 0.7112 0.6096)
			(layers "F.Cu" "F.Mask" "F.Paste")
			(net "XP1R2V_FB")
		)
		(zone
			(layer "F.Cu")
			(hatch none 0.5)
			(connect_pads
				(clearance 0)
			)
			(min_thickness 0.25)
			(keepout
				(tracks allowed)
				(vias not_allowed)
				(pads allowed)
				(copperpour not_allowed)
				(footprints allowed)
			)
			(placement
				(enabled no)
				(sheetname "")
			)
			(fill
				(thermal_gap 0.5)
				(thermal_bridge_width 0.5)
				(island_removal_mode 0)
			)
			(polygon
				(pts
					(xy 97.3836 -70.7898) (xy 97.3836 -70.1802) (xy 97.536 -70.1802) (xy 97.536 -70.7898)
				)
			)
		)
	)
	(footprint ""
		(layer "F.Cu")
		(at 115.062 -61.976 90)
		(property "Reference" "R339"
			(at 3.302 0.29337 90)
			(unlocked yes)
			(layer "F.SilkS")
			(effects
				(font
					(size 0.7874 0.5842)
					(thickness 0.1524)
				)
			)
		)
		(property "Value" "VAL*"
			(at 0.02032 2.13233 90)
			(unlocked yes)
			(layer "F.Fab")
			(hide yes)
			(effects
				(font
					(size 0.7874 0.5842)
					(thickness 0.1524)
				)
			)
		)
		(property "Tolerance" "TOL*"
			(at 0.044704 3.05435 90)
			(unlocked yes)
			(layer "Cmts.User")
			(hide yes)
			(effects
				(font
					(size 0.7874 0.5842)
					(thickness 0.1524)
				)
			)
		)
		(property "User Part Number" "PARTNUM*"
			(at 0.02032 4.024884 90)
			(unlocked yes)
			(layer "Cmts.User")
			(hide yes)
			(effects
				(font
					(size 0.7874 0.5842)
					(thickness 0.1524)
				)
			)
		)
		(property "Device Type" "RESISTOR-G155-133R0-01,33OHM,1%"
			(at 0.008382 1.210564 90)
			(unlocked yes)
			(layer "F.Fab")
			(hide yes)
			(effects
				(font
					(size 0.7874 0.5842)
					(thickness 0.1524)
				)
			)
		)
		(duplicate_pad_numbers_are_jumpers no)
		(fp_line
			(start 1.143 -0.5588)
			(end -1.143 -0.5588)
			(stroke
				(width 0.1)
				(type default)
			)
			(layer "F.SilkS")
		)
		(fp_line
			(start -1.143 -0.5588)
			(end -1.143 0.5588)
			(stroke
				(width 0.1)
				(type default)
			)
			(layer "F.SilkS")
		)
		(fp_line
			(start 1.143 0.5588)
			(end 1.143 -0.5588)
			(stroke
				(width 0.1)
				(type default)
			)
			(layer "F.SilkS")
		)
		(fp_line
			(start -1.143 0.5588)
			(end 1.143 0.5588)
			(stroke
				(width 0.1)
				(type default)
			)
			(layer "F.SilkS")
		)
		(fp_poly
			(pts
				(xy -1.143 0.5588) (xy 1.143 0.5588) (xy 1.143 -0.5588) (xy -1.143 -0.5588)
			)
			(stroke
				(width 0)
				(type default)
			)
			(fill no)
			(layer "F.CrtYd")
		)
		(fp_line
			(start 0.508 -0.3048)
			(end -0.508 -0.3048)
			(stroke
				(width 0.1)
				(type default)
			)
			(layer "F.Fab")
		)
		(fp_line
			(start -0.508 -0.3048)
			(end -0.508 0.3048)
			(stroke
				(width 0.1)
				(type default)
			)
			(layer "F.Fab")
		)
		(fp_line
			(start 0.508 0.3048)
			(end 0.508 -0.3048)
			(stroke
				(width 0.1)
				(type default)
			)
			(layer "F.Fab")
		)
		(fp_line
			(start -0.508 0.3048)
			(end 0.508 0.3048)
			(stroke
				(width 0.1)
				(type default)
			)
			(layer "F.Fab")
		)
		(pad "1" smd rect
			(at -0.5334 0 90)
			(size 0.7112 0.6096)
			(layers "F.Cu" "F.Mask" "F.Paste")
			(net "FPGA_D02")
		)
		(pad "2" smd rect
			(at 0.5334 0 90)
			(size 0.7112 0.6096)
			(layers "F.Cu" "F.Mask" "F.Paste")
			(net "FPGA_FLASH_DQ2")
		)
		(zone
			(layer "F.Cu")
			(hatch none 0.5)
			(connect_pads
				(clearance 0)
			)
			(min_thickness 0.25)
			(keepout
				(tracks not_allowed)
				(vias allowed)
				(pads allowed)
				(copperpour not_allowed)
				(footprints allowed)
			)
			(placement
				(enabled no)
				(sheetname "")
			)
			(fill
				(thermal_gap 0.5)
				(thermal_bridge_width 0.5)
				(island_removal_mode 0)
			)
			(polygon
				(pts
					(xy 115.3668 -61.8998) (xy 115.3668 -62.0522) (xy 114.7572 -62.0522) (xy 114.7572 -61.8998)
				)
			)
		)
		(zone
			(layer "F.Cu")
			(hatch none 0.5)
			(connect_pads
				(clearance 0)
			)
			(min_thickness 0.25)
			(keepout
				(tracks allowed)
				(vias not_allowed)
				(pads allowed)
				(copperpour not_allowed)
				(footprints allowed)
			)
			(placement
				(enabled no)
				(sheetname "")
			)
			(fill
				(thermal_gap 0.5)
				(thermal_bridge_width 0.5)
				(island_removal_mode 0)
			)
			(polygon
				(pts
					(xy 115.3668 -61.8998) (xy 115.3668 -62.0522) (xy 114.7572 -62.0522) (xy 114.7572 -61.8998)
				)
			)
		)
	)
	(footprint ""
		(layer "F.Cu")
		(at 141.605 -24.511 -90)
		(property "Reference" "C224"
			(at -3.556 -0.16637 90)
			(unlocked yes)
			(layer "F.SilkS")
			(effects
				(font
					(size 0.7874 0.5842)
					(thickness 0.1524)
				)
			)
		)
		(property "Value" "VAL*"
			(at 0.0762 3.134106 270)
			(unlocked yes)
			(layer "F.Fab")
			(hide yes)
			(effects
				(font
					(size 0.7874 0.5842)
					(thickness 0.1524)
				)
			)
		)
		(property "Tolerance" "TOL*"
			(at 0.0762 4.048506 270)
			(unlocked yes)
			(layer "Cmts.User")
			(hide yes)
			(effects
				(font
					(size 0.7874 0.5842)
					(thickness 0.1524)
				)
			)
		)
		(property "User Part Number" "PARTNUM*"
			(at 0.1016 5.013706 270)
			(unlocked yes)
			(layer "Cmts.User")
			(hide yes)
			(effects
				(font
					(size 0.7874 0.5842)
					(thickness 0.1524)
				)
			)
		)
		(property "Device Type" "CAPACITOR-G107-0F226-CM,22UF,2A"
			(at 0.0508 2.194306 270)
			(unlocked yes)
			(layer "F.Fab")
			(hide yes)
			(effects
				(font
					(size 0.7874 0.5842)
					(thickness 0.1524)
				)
			)
		)
		(duplicate_pad_numbers_are_jumpers no)
		(fp_line
			(start -1.5748 0.9398)
			(end 1.5748 0.9398)
			(stroke
				(width 0.1)
				(type default)
			)
			(layer "F.SilkS")
		)
		(fp_line
			(start 1.5748 0.9398)
			(end 1.5748 -0.9398)
			(stroke
				(width 0.1)
				(type default)
			)
			(layer "F.SilkS")
		)
		(fp_line
			(start -1.5748 -0.9398)
			(end -1.5748 0.9398)
			(stroke
				(width 0.1)
				(type default)
			)
			(layer "F.SilkS")
		)
		(fp_line
			(start 1.5748 -0.9398)
			(end -1.5748 -0.9398)
			(stroke
				(width 0.1)
				(type default)
			)
			(layer "F.SilkS")
		)
		(fp_rect
			(start -1.5748 -0.9398)
			(end 1.5748 0.9398)
			(stroke
				(width 0)
				(type default)
			)
			(fill no)
			(layer "F.CrtYd")
		)
		(fp_line
			(start -1.016 0.635)
			(end 1.016 0.635)
			(stroke
				(width 0.1)
				(type default)
			)
			(layer "F.Fab")
		)
		(fp_line
			(start 1.016 0.635)
			(end 1.016 -0.635)
			(stroke
				(width 0.1)
				(type default)
			)
			(layer "F.Fab")
		)
		(fp_line
			(start -1.016 -0.635)
			(end -1.016 0.635)
			(stroke
				(width 0.1)
				(type default)
			)
			(layer "F.Fab")
		)
		(fp_line
			(start 1.016 -0.635)
			(end -1.016 -0.635)
			(stroke
				(width 0.1)
				(type default)
			)
			(layer "F.Fab")
		)
		(pad "1" smd rect
			(at -0.8382 0 270)
			(size 0.9652 1.3716)
			(layers "F.Cu" "F.Mask" "F.Paste")
			(net "XP3R3V")
		)
		(pad "2" smd rect
			(at 0.8382 0 270)
			(size 0.9652 1.3716)
			(layers "F.Cu" "F.Mask" "F.Paste")
			(net "SG")
		)
		(zone
			(layer "F.Cu")
			(hatch none 0.5)
			(connect_pads
				(clearance 0)
			)
			(min_thickness 0.25)
			(keepout
				(tracks allowed)
				(vias not_allowed)
				(pads allowed)
				(copperpour not_allowed)
				(footprints allowed)
			)
			(placement
				(enabled no)
				(sheetname "")
			)
			(fill
				(thermal_gap 0.5)
				(thermal_bridge_width 0.5)
				(island_removal_mode 0)
			)
			(polygon
				(pts
					(xy 142.24 -24.7396) (xy 140.97 -24.7396) (xy 140.97 -24.2824) (xy 142.24 -24.2824)
				)
			)
		)
	)
)
